(kicad_pcb
	(version 20260206)
	(generator "pcbnew")
	(generator_version "10.0")
	(general
		(thickness 1.6)
		(legacy_teardrops no)
	)
	(paper "A4")
	(title_block
		(title "03242023_DA0F0TMBIJ0_F0T_Motherboard_J_brd_V01_OCP.brd")
		(comment 1 "Grand Teton / footprints 3672-3678 of 6105")
	)
	(layers
		(0 "F.Cu" signal "TOP")
		(4 "In1.Cu" signal "GND")
		(6 "In2.Cu" signal "IN1")
		(8 "In3.Cu" signal "GND1")
		(10 "In4.Cu" signal "IN2")
		(12 "In5.Cu" signal "GND2")
		(14 "In6.Cu" signal "IN3")
		(16 "In7.Cu" signal "GND3")
		(18 "In8.Cu" signal "VCC")
		(20 "In9.Cu" signal "VCC1")
		(22 "In10.Cu" signal "GND4")
		(24 "In11.Cu" signal "IN4")
		(26 "In12.Cu" signal "GND5")
		(28 "In13.Cu" signal "IN5")
		(30 "In14.Cu" signal "GND6")
		(32 "In15.Cu" signal "IN6")
		(34 "In16.Cu" signal "GND7")
		(2 "B.Cu" signal "BOTTOM")
		(9 "F.Adhes" user "F.Adhesive")
		(11 "B.Adhes" user "B.Adhesive")
		(13 "F.Paste" user "Package Geometry/Pastemask Top")
		(15 "B.Paste" user "Package Geometry/Pastemask Bottom")
		(5 "F.SilkS" user "Ref Des/Silkscreen Top")
		(7 "B.SilkS" user "Ref Des/Silkscreen Bottom")
		(1 "F.Mask" user "Board Geometry/Soldermask Top")
		(3 "B.Mask" user "Board Geometry/Soldermask Bottom")
		(17 "Dwgs.User" user "User.Drawings")
		(19 "Cmts.User" user "User.Comments")
		(21 "Eco1.User" user "User.Eco1")
		(23 "Eco2.User" user "User.Eco2")
		(25 "Edge.Cuts" user "Board Geometry/Outline")
		(27 "Margin" user)
		(31 "F.CrtYd" user "Package Geometry/Place Bound Top")
		(29 "B.CrtYd" user "Package Geometry/Place Bound Bottom")
		(35 "F.Fab" user "Ref Des/Assembly Top")
		(33 "B.Fab" user "Ref Des/Assembly Bottom")
	)
	(footprint ""
		(layer "F.Cu")
		(at 40.627554 -108.047282)
		(property "Reference" "R3683"
			(at 0 0 0)
			(layer "F.SilkS")
			(hide yes)
			(effects
				(font
					(size 1.27 1.27)
				)
			)
		)
		(property "Value" ""
			(at 0 0 0)
			(layer "F.Fab")
			(effects
				(font
					(size 1.27 1.27)
				)
			)
		)
		(duplicate_pad_numbers_are_jumpers no)
		(fp_line
			(start -0.7874 -0.4064)
			(end 0.7874 -0.4064)
			(stroke
				(width 0.1524)
				(type default)
			)
			(layer "F.SilkS")
		)
		(fp_line
			(start -0.7874 0.4064)
			(end -0.7874 -0.4064)
			(stroke
				(width 0.1524)
				(type default)
			)
			(layer "F.SilkS")
		)
		(fp_line
			(start 0.7874 -0.4064)
			(end 0.7874 0.4064)
			(stroke
				(width 0.1524)
				(type default)
			)
			(layer "F.SilkS")
		)
		(fp_line
			(start 0.7874 0.4064)
			(end -0.7874 0.4064)
			(stroke
				(width 0.1524)
				(type default)
			)
			(layer "F.SilkS")
		)
		(fp_line
			(start -0.67945 -0.305054)
			(end -0.12065 -0.305054)
			(stroke
				(width 0.1)
				(type default)
			)
			(layer "F.Fab")
		)
		(fp_line
			(start -0.67945 0.3048)
			(end -0.67945 -0.305054)
			(stroke
				(width 0.1)
				(type default)
			)
			(layer "F.Fab")
		)
		(fp_line
			(start -0.12065 -0.305054)
			(end -0.12065 -0.2794)
			(stroke
				(width 0.1)
				(type default)
			)
			(layer "F.Fab")
		)
		(fp_line
			(start -0.12065 -0.2794)
			(end 0.12065 -0.2794)
			(stroke
				(width 0.1)
				(type default)
			)
			(layer "F.Fab")
		)
		(fp_line
			(start -0.12065 0.2794)
			(end -0.12065 0.3048)
			(stroke
				(width 0.1)
				(type default)
			)
			(layer "F.Fab")
		)
		(fp_line
			(start -0.12065 0.3048)
			(end -0.67945 0.3048)
			(stroke
				(width 0.1)
				(type default)
			)
			(layer "F.Fab")
		)
		(fp_line
			(start 0.120396 0.2794)
			(end -0.12065 0.2794)
			(stroke
				(width 0.1)
				(type default)
			)
			(layer "F.Fab")
		)
		(fp_line
			(start 0.120396 0.3048)
			(end 0.120396 0.2794)
			(stroke
				(width 0.1)
				(type default)
			)
			(layer "F.Fab")
		)
		(fp_line
			(start 0.12065 -0.3048)
			(end 0.67945 -0.3048)
			(stroke
				(width 0.1)
				(type default)
			)
			(layer "F.Fab")
		)
		(fp_line
			(start 0.12065 -0.2794)
			(end 0.12065 -0.3048)
			(stroke
				(width 0.1)
				(type default)
			)
			(layer "F.Fab")
		)
		(fp_line
			(start 0.67945 -0.3048)
			(end 0.67945 0.3048)
			(stroke
				(width 0.1)
				(type default)
			)
			(layer "F.Fab")
		)
		(fp_line
			(start 0.67945 0.3048)
			(end 0.120396 0.3048)
			(stroke
				(width 0.1)
				(type default)
			)
			(layer "F.Fab")
		)
		(pad "1" smd rect
			(at -0.40005 0 180)
			(size 0.4572 0.508)
			(layers "F.Cu" "F.Mask" "F.Paste")
			(net "P3V3_ADC")
		)
		(pad "2" smd rect
			(at 0.40005 0 180)
			(size 0.4572 0.508)
			(layers "F.Cu" "F.Mask" "F.Paste")
			(net "P3V3_ADC_MAM")
		)
	)
	(footprint ""
		(layer "F.Cu")
		(at 218.205304 -59.453272 180)
		(property "Reference" "PC2220"
			(at 0 0 180)
			(layer "F.SilkS")
			(hide yes)
			(effects
				(font
					(size 1.27 1.27)
				)
			)
		)
		(property "Value" ""
			(at 0 0 180)
			(layer "F.Fab")
			(effects
				(font
					(size 1.27 1.27)
				)
			)
		)
		(duplicate_pad_numbers_are_jumpers no)
		(fp_line
			(start 1.524 0.762)
			(end -1.524 0.762)
			(stroke
				(width 0.1524)
				(type default)
			)
			(layer "F.SilkS")
		)
		(fp_line
			(start 1.524 -0.762)
			(end 1.524 0.762)
			(stroke
				(width 0.1524)
				(type default)
			)
			(layer "F.SilkS")
		)
		(fp_line
			(start -1.524 0.762)
			(end -1.524 -0.762)
			(stroke
				(width 0.1524)
				(type default)
			)
			(layer "F.SilkS")
		)
		(fp_line
			(start -1.524 -0.762)
			(end 1.524 -0.762)
			(stroke
				(width 0.1524)
				(type default)
			)
			(layer "F.SilkS")
		)
		(fp_line
			(start 1.1049 0.724916)
			(end 1.1049 -0.724916)
			(stroke
				(width 0.1)
				(type default)
			)
			(layer "F.Fab")
		)
		(fp_line
			(start 1.1049 -0.724916)
			(end -1.1049 -0.724916)
			(stroke
				(width 0.1)
				(type default)
			)
			(layer "F.Fab")
		)
		(fp_line
			(start -1.1049 0.724916)
			(end 1.1049 0.724916)
			(stroke
				(width 0.1)
				(type default)
			)
			(layer "F.Fab")
		)
		(fp_line
			(start -1.1049 -0.724916)
			(end -1.1049 0.724916)
			(stroke
				(width 0.1)
				(type default)
			)
			(layer "F.Fab")
		)
		(pad "1" smd rect
			(at -0.889 0)
			(size 1.016 1.27)
			(layers "F.Cu" "F.Mask" "F.Paste")
			(net "P3V3_E1S_0_R")
		)
		(pad "2" smd rect
			(at 0.889 0)
			(size 1.016 1.27)
			(layers "F.Cu" "F.Mask" "F.Paste")
			(net "GND")
		)
	)
	(footprint ""
		(layer "F.Cu")
		(at 176.059338 -414.697418)
		(property "Reference" "R3431"
			(at 0 0 0)
			(layer "F.SilkS")
			(hide yes)
			(effects
				(font
					(size 1.27 1.27)
				)
			)
		)
		(property "Value" ""
			(at 0 0 0)
			(layer "F.Fab")
			(effects
				(font
					(size 1.27 1.27)
				)
			)
		)
		(duplicate_pad_numbers_are_jumpers no)
		(fp_line
			(start -0.7874 -0.4064)
			(end 0.7874 -0.4064)
			(stroke
				(width 0.1524)
				(type default)
			)
			(layer "F.SilkS")
		)
		(fp_line
			(start -0.7874 0.4064)
			(end -0.7874 -0.4064)
			(stroke
				(width 0.1524)
				(type default)
			)
			(layer "F.SilkS")
		)
		(fp_line
			(start 0.7874 -0.4064)
			(end 0.7874 0.4064)
			(stroke
				(width 0.1524)
				(type default)
			)
			(layer "F.SilkS")
		)
		(fp_line
			(start 0.7874 0.4064)
			(end -0.7874 0.4064)
			(stroke
				(width 0.1524)
				(type default)
			)
			(layer "F.SilkS")
		)
		(fp_line
			(start -0.67945 -0.305054)
			(end -0.12065 -0.305054)
			(stroke
				(width 0.1)
				(type default)
			)
			(layer "F.Fab")
		)
		(fp_line
			(start -0.67945 0.3048)
			(end -0.67945 -0.305054)
			(stroke
				(width 0.1)
				(type default)
			)
			(layer "F.Fab")
		)
		(fp_line
			(start -0.12065 -0.305054)
			(end -0.12065 -0.2794)
			(stroke
				(width 0.1)
				(type default)
			)
			(layer "F.Fab")
		)
		(fp_line
			(start -0.12065 -0.2794)
			(end 0.12065 -0.2794)
			(stroke
				(width 0.1)
				(type default)
			)
			(layer "F.Fab")
		)
		(fp_line
			(start -0.12065 0.2794)
			(end -0.12065 0.3048)
			(stroke
				(width 0.1)
				(type default)
			)
			(layer "F.Fab")
		)
		(fp_line
			(start -0.12065 0.3048)
			(end -0.67945 0.3048)
			(stroke
				(width 0.1)
				(type default)
			)
			(layer "F.Fab")
		)
		(fp_line
			(start 0.120396 0.2794)
			(end -0.12065 0.2794)
			(stroke
				(width 0.1)
				(type default)
			)
			(layer "F.Fab")
		)
		(fp_line
			(start 0.120396 0.3048)
			(end 0.120396 0.2794)
			(stroke
				(width 0.1)
				(type default)
			)
			(layer "F.Fab")
		)
		(fp_line
			(start 0.12065 -0.3048)
			(end 0.67945 -0.3048)
			(stroke
				(width 0.1)
				(type default)
			)
			(layer "F.Fab")
		)
		(fp_line
			(start 0.12065 -0.2794)
			(end 0.12065 -0.3048)
			(stroke
				(width 0.1)
				(type default)
			)
			(layer "F.Fab")
		)
		(fp_line
			(start 0.67945 -0.3048)
			(end 0.67945 0.3048)
			(stroke
				(width 0.1)
				(type default)
			)
			(layer "F.Fab")
		)
		(fp_line
			(start 0.67945 0.3048)
			(end 0.120396 0.3048)
			(stroke
				(width 0.1)
				(type default)
			)
			(layer "F.Fab")
		)
		(pad "1" smd circle
			(at -0.40005 0)
			(size 0 0)
			(layers "F.Cu" "F.Mask" "F.Paste")
			(net "GPU_HMC_PRSNT_N")
		)
		(pad "2" smd circle
			(at 0.40005 0)
			(size 0 0)
			(layers "F.Cu" "F.Mask" "F.Paste")
			(net "GND")
		)
	)
	(footprint ""
		(layer "F.Cu")
		(at 88.690958 -402.371052 -90)
		(property "Reference" "C737"
			(at 0 0 270)
			(layer "F.SilkS")
			(hide yes)
			(effects
				(font
					(size 1.27 1.27)
				)
			)
		)
		(property "Value" ""
			(at 0 0 270)
			(layer "F.Fab")
			(effects
				(font
					(size 1.27 1.27)
				)
			)
		)
		(duplicate_pad_numbers_are_jumpers no)
		(fp_line
			(start -0.299974 0.150114)
			(end -0.299974 -0.150114)
			(stroke
				(width 0.1)
				(type default)
			)
			(layer "F.Fab")
		)
		(fp_line
			(start 0.299974 0.150114)
			(end -0.299974 0.150114)
			(stroke
				(width 0.1)
				(type default)
			)
			(layer "F.Fab")
		)
		(fp_line
			(start -0.299974 -0.150114)
			(end 0.299974 -0.150114)
			(stroke
				(width 0.1)
				(type default)
			)
			(layer "F.Fab")
		)
		(fp_line
			(start 0.299974 -0.150114)
			(end 0.299974 0.150114)
			(stroke
				(width 0.1)
				(type default)
			)
			(layer "F.Fab")
		)
		(pad "1" smd rect
			(at -0.2667 0 270)
			(size 0.3048 0.381)
			(layers "F.Cu" "F.Mask" "F.Paste")
			(net "P5E_CPU1_PE0_TX_C_DP<2>")
		)
		(pad "2" smd rect
			(at 0.2667 0 270)
			(size 0.3048 0.381)
			(layers "F.Cu" "F.Mask" "F.Paste")
			(net "P5E_CPU1_PE0_TX_DP<2>")
		)
	)
	(footprint ""
		(layer "F.Cu")
		(at 433.33289 -135.029702 180)
		(property "Reference" "R2398"
			(at 0 0 180)
			(layer "F.SilkS")
			(hide yes)
			(effects
				(font
					(size 1.27 1.27)
				)
			)
		)
		(property "Value" ""
			(at 0 0 180)
			(layer "F.Fab")
			(effects
				(font
					(size 1.27 1.27)
				)
			)
		)
		(duplicate_pad_numbers_are_jumpers no)
		(fp_line
			(start 0.7874 0.4064)
			(end -0.7874 0.4064)
			(stroke
				(width 0.1524)
				(type default)
			)
			(layer "F.SilkS")
		)
		(fp_line
			(start 0.7874 -0.4064)
			(end 0.7874 0.4064)
			(stroke
				(width 0.1524)
				(type default)
			)
			(layer "F.SilkS")
		)
		(fp_line
			(start -0.7874 0.4064)
			(end -0.7874 -0.4064)
			(stroke
				(width 0.1524)
				(type default)
			)
			(layer "F.SilkS")
		)
		(fp_line
			(start -0.7874 -0.4064)
			(end 0.7874 -0.4064)
			(stroke
				(width 0.1524)
				(type default)
			)
			(layer "F.SilkS")
		)
		(fp_line
			(start 0.67945 0.3048)
			(end 0.120396 0.3048)
			(stroke
				(width 0.1)
				(type default)
			)
			(layer "F.Fab")
		)
		(fp_line
			(start 0.67945 -0.3048)
			(end 0.67945 0.3048)
			(stroke
				(width 0.1)
				(type default)
			)
			(layer "F.Fab")
		)
		(fp_line
			(start 0.12065 -0.2794)
			(end 0.12065 -0.3048)
			(stroke
				(width 0.1)
				(type default)
			)
			(layer "F.Fab")
		)
		(fp_line
			(start 0.12065 -0.3048)
			(end 0.67945 -0.3048)
			(stroke
				(width 0.1)
				(type default)
			)
			(layer "F.Fab")
		)
		(fp_line
			(start 0.120396 0.3048)
			(end 0.120396 0.2794)
			(stroke
				(width 0.1)
				(type default)
			)
			(layer "F.Fab")
		)
		(fp_line
			(start 0.120396 0.2794)
			(end -0.12065 0.2794)
			(stroke
				(width 0.1)
				(type default)
			)
			(layer "F.Fab")
		)
		(fp_line
			(start -0.12065 0.3048)
			(end -0.67945 0.3048)
			(stroke
				(width 0.1)
				(type default)
			)
			(layer "F.Fab")
		)
		(fp_line
			(start -0.12065 0.2794)
			(end -0.12065 0.3048)
			(stroke
				(width 0.1)
				(type default)
			)
			(layer "F.Fab")
		)
		(fp_line
			(start -0.12065 -0.2794)
			(end 0.12065 -0.2794)
			(stroke
				(width 0.1)
				(type default)
			)
			(layer "F.Fab")
		)
		(fp_line
			(start -0.12065 -0.305054)
			(end -0.12065 -0.2794)
			(stroke
				(width 0.1)
				(type default)
			)
			(layer "F.Fab")
		)
		(fp_line
			(start -0.67945 0.3048)
			(end -0.67945 -0.305054)
			(stroke
				(width 0.1)
				(type default)
			)
			(layer "F.Fab")
		)
		(fp_line
			(start -0.67945 -0.305054)
			(end -0.12065 -0.305054)
			(stroke
				(width 0.1)
				(type default)
			)
			(layer "F.Fab")
		)
		(pad "1" smd circle
			(at -0.40005 0 180)
			(size 0 0)
			(layers "F.Cu" "F.Mask" "F.Paste")
			(net "P3V3_AUX")
		)
		(pad "2" smd circle
			(at 0.40005 0 180)
			(size 0 0)
			(layers "F.Cu" "F.Mask" "F.Paste")
			(net "IRQ_PVCCFA_CPU0_VRHOT_R_N")
		)
	)
	(footprint ""
		(layer "F.Cu")
		(at 464.01355 -45.669708)
		(property "Reference" "U82"
			(at -0.0127 1.719072 0)
			(unlocked yes)
			(layer "F.SilkS")
			(effects
				(font
					(size 0.7874 0.5842)
					(thickness 0.1524)
				)
				(justify left)
			)
		)
		(property "Value" ""
			(at 0 0 0)
			(layer "F.Fab")
			(effects
				(font
					(size 1.27 1.27)
				)
			)
		)
		(duplicate_pad_numbers_are_jumpers no)
		(fp_line
			(start -1.400048 1.100074)
			(end -1.400048 -1.100074)
			(stroke
				(width 0.1524)
				(type default)
			)
			(layer "F.SilkS")
		)
		(fp_line
			(start 1.400048 -1.100074)
			(end -1.400048 -1.100074)
			(stroke
				(width 0.1524)
				(type default)
			)
			(layer "F.SilkS")
		)
		(fp_line
			(start 1.400048 -1.100074)
			(end 1.400048 1.100074)
			(stroke
				(width 0.1524)
				(type default)
			)
			(layer "F.SilkS")
		)
		(fp_line
			(start 1.400048 1.100074)
			(end -1.400048 1.100074)
			(stroke
				(width 0.1524)
				(type default)
			)
			(layer "F.SilkS")
		)
		(fp_poly
			(pts
				(xy -2.606548 -0.141986) (xy -2.606548 -1.157986) (xy -1.590548 -0.649986)
			)
			(stroke
				(width 0)
				(type default)
			)
			(fill yes)
			(layer "F.SilkS")
		)
		(fp_line
			(start -0.674878 -1.100074)
			(end 0.674878 -1.100074)
			(stroke
				(width 0.1)
				(type default)
			)
			(layer "F.Fab")
		)
		(fp_line
			(start -0.674878 1.100074)
			(end -0.674878 -1.100074)
			(stroke
				(width 0.1)
				(type default)
			)
			(layer "F.Fab")
		)
		(fp_line
			(start 0.674878 -1.100074)
			(end 0.674878 1.100074)
			(stroke
				(width 0.1)
				(type default)
			)
			(layer "F.Fab")
		)
		(fp_line
			(start 0.674878 1.100074)
			(end -0.674878 1.100074)
			(stroke
				(width 0.1)
				(type default)
			)
			(layer "F.Fab")
		)
		(fp_poly
			(pts
				(xy -1.590548 -0.649986) (xy -2.606548 -1.157986) (xy -2.606548 -0.141986)
			)
			(stroke
				(width 0)
				(type default)
			)
			(fill yes)
			(layer "F.Fab")
		)
		(pad "1" smd rect
			(at -0.94996 -0.649986 270)
			(size 0.4318 0.6096)
			(layers "F.Cu" "F.Mask" "F.Paste")
			(net "PU_OCP_SFF_WAKE_OE")
		)
		(pad "2" smd rect
			(at -0.94996 0 270)
			(size 0.4318 0.6096)
			(layers "F.Cu" "F.Mask" "F.Paste")
			(net "IRQ_LVC3_OCP_SFF_WAKE_N")
		)
		(pad "3" smd rect
			(at -0.94996 0.649986 270)
			(size 0.4318 0.6096)
			(layers "F.Cu" "F.Mask" "F.Paste")
			(net "GND")
		)
		(pad "4" smd rect
			(at 0.94996 0.649986 270)
			(size 0.4318 0.6096)
			(layers "F.Cu" "F.Mask" "F.Paste")
			(net "OCP_SFF_WAKE_BUFF_N")
		)
		(pad "5" smd rect
			(at 0.94996 -0.649986 270)
			(size 0.4318 0.6096)
			(layers "F.Cu" "F.Mask" "F.Paste")
			(net "P3V3_AUX")
		)
	)
	(footprint ""
		(layer "F.Cu")
		(at 116.71808 -397.747998 -90)
		(property "Reference" "Q75"
			(at 0.64516 -1.48082 0)
			(unlocked yes)
			(layer "F.SilkS")
			(effects
				(font
					(size 0.7874 0.5842)
					(thickness 0.1524)
				)
				(justify left)
			)
		)
		(property "Value" ""
			(at 0 0 270)
			(layer "F.Fab")
			(effects
				(font
					(size 1.27 1.27)
				)
			)
		)
		(duplicate_pad_numbers_are_jumpers no)
		(fp_line
			(start -1.332738 1.100074)
			(end -1.332738 -1.100074)
			(stroke
				(width 0.1524)
				(type default)
			)
			(layer "F.SilkS")
		)
		(fp_line
			(start 1.332738 1.100074)
			(end -1.332738 1.100074)
			(stroke
				(width 0.1524)
				(type default)
			)
			(layer "F.SilkS")
		)
		(fp_line
			(start 0 -0.541274)
			(end 0.4826 -1.100074)
			(stroke
				(width 0.1524)
				(type default)
			)
			(layer "F.SilkS")
		)
		(fp_line
			(start -1.332738 -1.100074)
			(end -0.4826 -1.100074)
			(stroke
				(width 0.1524)
				(type default)
			)
			(layer "F.SilkS")
		)
		(fp_line
			(start -0.4826 -1.100074)
			(end 0 -0.541274)
			(stroke
				(width 0.1524)
				(type default)
			)
			(layer "F.SilkS")
		)
		(fp_line
			(start 0.4826 -1.100074)
			(end 1.332738 -1.100074)
			(stroke
				(width 0.1524)
				(type default)
			)
			(layer "F.SilkS")
		)
		(fp_line
			(start 1.332738 -1.100074)
			(end 1.332738 1.100074)
			(stroke
				(width 0.1524)
				(type default)
			)
			(layer "F.SilkS")
		)
		(fp_poly
			(pts
				(xy -0.801116 -2.02311) (xy -1.152144 -1.321054) (xy -1.503172 -2.02311)
			)
			(stroke
				(width 0)
				(type default)
			)
			(fill yes)
			(layer "F.SilkS")
		)
		(fp_line
			(start -0.674878 1.100074)
			(end -0.674878 -1.100074)
			(stroke
				(width 0.1)
				(type default)
			)
			(layer "F.Fab")
		)
		(fp_line
			(start 0.674878 1.100074)
			(end -0.674878 1.100074)
			(stroke
				(width 0.1)
				(type default)
			)
			(layer "F.Fab")
		)
		(fp_line
			(start -0.674878 -1.100074)
			(end 0.674878 -1.100074)
			(stroke
				(width 0.1)
				(type default)
			)
			(layer "F.Fab")
		)
		(fp_line
			(start 0.674878 -1.100074)
			(end 0.674878 1.100074)
			(stroke
				(width 0.1)
				(type default)
			)
			(layer "F.Fab")
		)
		(fp_poly
			(pts
				(xy -2.2352 -0.298958) (xy -2.2352 -1.001014) (xy -1.533144 -0.649986)
			)
			(stroke
				(width 0)
				(type default)
			)
			(fill yes)
			(layer "F.Fab")
		)
		(pad "1" smd rect
			(at -0.94996 -0.649986)
			(size 0.4318 0.508)
			(layers "F.Cu" "F.Mask" "F.Paste")
			(net "GND")
		)
		(pad "2" smd rect
			(at -0.94996 0)
			(size 0.4318 0.508)
			(layers "F.Cu" "F.Mask" "F.Paste")
			(net "FM_SMB_1_ALERT_GPU_N")
		)
		(pad "3" smd rect
			(at -0.94996 0.649986)
			(size 0.4318 0.508)
			(layers "F.Cu" "F.Mask" "F.Paste")
			(net "FM_SMB_1_ALERT_GPU_ISO_N")
		)
		(pad "4" smd rect
			(at 0.94996 0.649986)
			(size 0.4318 0.508)
			(layers "F.Cu" "F.Mask" "F.Paste")
			(net "GND")
		)
		(pad "5" smd rect
			(at 0.94996 0)
			(size 0.4318 0.508)
			(layers "F.Cu" "F.Mask" "F.Paste")
			(net "FM_SMB_1_ALERT_GPU")
		)
		(pad "6" smd rect
			(at 0.94996 -0.649986)
			(size 0.4318 0.508)
			(layers "F.Cu" "F.Mask" "F.Paste")
			(net "FM_SMB_1_ALERT_GPU")
		)
	)
)
